(kicad_pcb
	(version 20260206)
	(generator "pcbnew")
	(generator_version "10.0")
	(general
		(thickness 1.6)
		(legacy_teardrops no)
	)
	(paper "A4")
	(title_block
		(title "01162023_DA0F0TEBIF0_F0T_Expander_BD_F_brd_V02_OCP.brd")
		(comment 1 "Grand Teton / footprints 6603-6608 of 9728")
	)
	(layers
		(0 "F.Cu" signal "TOP")
		(4 "In1.Cu" signal "GND")
		(6 "In2.Cu" signal "VCC")
		(8 "In3.Cu" signal "VCC1")
		(10 "In4.Cu" signal "GND1")
		(12 "In5.Cu" signal "IN1")
		(14 "In6.Cu" signal "GND2")
		(16 "In7.Cu" signal "IN2")
		(18 "In8.Cu" signal "GND3")
		(20 "In9.Cu" signal "IN3")
		(22 "In10.Cu" signal "GND4")
		(24 "In11.Cu" signal "IN4")
		(26 "In12.Cu" signal "GND5")
		(28 "In13.Cu" signal "IN5")
		(30 "In14.Cu" signal "GND6")
		(32 "In15.Cu" signal "IN6")
		(34 "In16.Cu" signal "GND7")
		(2 "B.Cu" signal "BOTTOM")
		(9 "F.Adhes" user "F.Adhesive")
		(11 "B.Adhes" user "B.Adhesive")
		(13 "F.Paste" user "Package Geometry/Pastemask Top")
		(15 "B.Paste" user "Package Geometry/Pastemask Bottom")
		(5 "F.SilkS" user "Ref Des/Silkscreen Top")
		(7 "B.SilkS" user "Ref Des/Silkscreen Bottom")
		(1 "F.Mask" user "Board Geometry/Soldermask Top")
		(3 "B.Mask" user "Board Geometry/Soldermask Bottom")
		(17 "Dwgs.User" user "User.Drawings")
		(19 "Cmts.User" user "User.Comments")
		(21 "Eco1.User" user "User.Eco1")
		(23 "Eco2.User" user "User.Eco2")
		(25 "Edge.Cuts" user "Board Geometry/Outline")
		(27 "Margin" user)
		(31 "F.CrtYd" user "Package Geometry/Place Bound Top")
		(29 "B.CrtYd" user "Package Geometry/Place Bound Bottom")
		(35 "F.Fab" user "Ref Des/Assembly Top")
		(33 "B.Fab" user "Ref Des/Assembly Bottom")
	)
	(footprint ""
		(layer "F.Cu")
		(at 248.559574 -146.642328 -90)
		(property "Reference" "C916"
			(at 0 0 270)
			(layer "F.SilkS")
			(hide yes)
			(effects
				(font
					(size 1.27 1.27)
				)
			)
		)
		(property "Value" ""
			(at 0 0 270)
			(layer "F.Fab")
			(effects
				(font
					(size 1.27 1.27)
				)
			)
		)
		(duplicate_pad_numbers_are_jumpers no)
		(fp_line
			(start -0.7874 0.4064)
			(end -0.7874 -0.4064)
			(stroke
				(width 0.1524)
				(type default)
			)
			(layer "F.SilkS")
		)
		(fp_line
			(start 0.7874 0.4064)
			(end -0.7874 0.4064)
			(stroke
				(width 0.1524)
				(type default)
			)
			(layer "F.SilkS")
		)
		(fp_line
			(start -0.7874 -0.4064)
			(end 0.7874 -0.4064)
			(stroke
				(width 0.1524)
				(type default)
			)
			(layer "F.SilkS")
		)
		(fp_line
			(start 0.7874 -0.4064)
			(end 0.7874 0.4064)
			(stroke
				(width 0.1524)
				(type default)
			)
			(layer "F.SilkS")
		)
		(fp_line
			(start -0.67945 0.3048)
			(end -0.67945 -0.305054)
			(stroke
				(width 0.1)
				(type default)
			)
			(layer "F.Fab")
		)
		(fp_line
			(start -0.12065 0.3048)
			(end -0.67945 0.3048)
			(stroke
				(width 0.1)
				(type default)
			)
			(layer "F.Fab")
		)
		(fp_line
			(start 0.120396 0.3048)
			(end 0.120396 0.2794)
			(stroke
				(width 0.1)
				(type default)
			)
			(layer "F.Fab")
		)
		(fp_line
			(start 0.67945 0.3048)
			(end 0.120396 0.3048)
			(stroke
				(width 0.1)
				(type default)
			)
			(layer "F.Fab")
		)
		(fp_line
			(start -0.12065 0.2794)
			(end -0.12065 0.3048)
			(stroke
				(width 0.1)
				(type default)
			)
			(layer "F.Fab")
		)
		(fp_line
			(start 0.120396 0.2794)
			(end -0.12065 0.2794)
			(stroke
				(width 0.1)
				(type default)
			)
			(layer "F.Fab")
		)
		(fp_line
			(start -0.12065 -0.2794)
			(end 0.12065 -0.2794)
			(stroke
				(width 0.1)
				(type default)
			)
			(layer "F.Fab")
		)
		(fp_line
			(start 0.12065 -0.2794)
			(end 0.12065 -0.3048)
			(stroke
				(width 0.1)
				(type default)
			)
			(layer "F.Fab")
		)
		(fp_line
			(start 0.12065 -0.3048)
			(end 0.67945 -0.3048)
			(stroke
				(width 0.1)
				(type default)
			)
			(layer "F.Fab")
		)
		(fp_line
			(start 0.67945 -0.3048)
			(end 0.67945 0.3048)
			(stroke
				(width 0.1)
				(type default)
			)
			(layer "F.Fab")
		)
		(fp_line
			(start -0.67945 -0.305054)
			(end -0.12065 -0.305054)
			(stroke
				(width 0.1)
				(type default)
			)
			(layer "F.Fab")
		)
		(fp_line
			(start -0.12065 -0.305054)
			(end -0.12065 -0.2794)
			(stroke
				(width 0.1)
				(type default)
			)
			(layer "F.Fab")
		)
		(pad "1" smd circle
			(at -0.40005 0 270)
			(size 0 0)
			(layers "F.Cu" "F.Mask" "F.Paste")
			(net "P3V3_AUX")
		)
		(pad "2" smd circle
			(at 0.40005 0 270)
			(size 0 0)
			(layers "F.Cu" "F.Mask" "F.Paste")
			(net "GND")
		)
	)
	(footprint ""
		(layer "F.Cu")
		(at 56.339486 -155.822904 90)
		(property "Reference" "R45"
			(at 0 0 90)
			(layer "F.SilkS")
			(hide yes)
			(effects
				(font
					(size 1.27 1.27)
				)
			)
		)
		(property "Value" ""
			(at 0 0 90)
			(layer "F.Fab")
			(effects
				(font
					(size 1.27 1.27)
				)
			)
		)
		(duplicate_pad_numbers_are_jumpers no)
		(fp_line
			(start 0.7874 -0.4064)
			(end 0.7874 0.4064)
			(stroke
				(width 0.1524)
				(type default)
			)
			(layer "F.SilkS")
		)
		(fp_line
			(start -0.7874 -0.4064)
			(end 0.7874 -0.4064)
			(stroke
				(width 0.1524)
				(type default)
			)
			(layer "F.SilkS")
		)
		(fp_line
			(start 0.7874 0.4064)
			(end -0.7874 0.4064)
			(stroke
				(width 0.1524)
				(type default)
			)
			(layer "F.SilkS")
		)
		(fp_line
			(start -0.7874 0.4064)
			(end -0.7874 -0.4064)
			(stroke
				(width 0.1524)
				(type default)
			)
			(layer "F.SilkS")
		)
		(fp_line
			(start -0.12065 -0.305054)
			(end -0.12065 -0.2794)
			(stroke
				(width 0.1)
				(type default)
			)
			(layer "F.Fab")
		)
		(fp_line
			(start -0.67945 -0.305054)
			(end -0.12065 -0.305054)
			(stroke
				(width 0.1)
				(type default)
			)
			(layer "F.Fab")
		)
		(fp_line
			(start 0.67945 -0.3048)
			(end 0.67945 0.3048)
			(stroke
				(width 0.1)
				(type default)
			)
			(layer "F.Fab")
		)
		(fp_line
			(start 0.12065 -0.3048)
			(end 0.67945 -0.3048)
			(stroke
				(width 0.1)
				(type default)
			)
			(layer "F.Fab")
		)
		(fp_line
			(start 0.12065 -0.2794)
			(end 0.12065 -0.3048)
			(stroke
				(width 0.1)
				(type default)
			)
			(layer "F.Fab")
		)
		(fp_line
			(start -0.12065 -0.2794)
			(end 0.12065 -0.2794)
			(stroke
				(width 0.1)
				(type default)
			)
			(layer "F.Fab")
		)
		(fp_line
			(start 0.120396 0.2794)
			(end -0.12065 0.2794)
			(stroke
				(width 0.1)
				(type default)
			)
			(layer "F.Fab")
		)
		(fp_line
			(start -0.12065 0.2794)
			(end -0.12065 0.3048)
			(stroke
				(width 0.1)
				(type default)
			)
			(layer "F.Fab")
		)
		(fp_line
			(start 0.67945 0.3048)
			(end 0.120396 0.3048)
			(stroke
				(width 0.1)
				(type default)
			)
			(layer "F.Fab")
		)
		(fp_line
			(start 0.120396 0.3048)
			(end 0.120396 0.2794)
			(stroke
				(width 0.1)
				(type default)
			)
			(layer "F.Fab")
		)
		(fp_line
			(start -0.12065 0.3048)
			(end -0.67945 0.3048)
			(stroke
				(width 0.1)
				(type default)
			)
			(layer "F.Fab")
		)
		(fp_line
			(start -0.67945 0.3048)
			(end -0.67945 -0.305054)
			(stroke
				(width 0.1)
				(type default)
			)
			(layer "F.Fab")
		)
		(pad "1" smd circle
			(at -0.40005 0 90)
			(size 0 0)
			(layers "F.Cu" "F.Mask" "F.Paste")
			(net "RST_NIC0_PERST0_R_N")
		)
		(pad "2" smd circle
			(at 0.40005 0 90)
			(size 0 0)
			(layers "F.Cu" "F.Mask" "F.Paste")
			(net "RST_HP_NIC0_BUF_N")
		)
	)
	(footprint ""
		(layer "F.Cu")
		(at 104.932734 -237.306612 90)
		(property "Reference" "PC293"
			(at 0 0 90)
			(layer "F.SilkS")
			(hide yes)
			(effects
				(font
					(size 1.27 1.27)
				)
			)
		)
		(property "Value" ""
			(at 0 0 90)
			(layer "F.Fab")
			(effects
				(font
					(size 1.27 1.27)
				)
			)
		)
		(duplicate_pad_numbers_are_jumpers no)
		(fp_line
			(start 1.524 -0.762)
			(end 1.524 0.762)
			(stroke
				(width 0.1524)
				(type default)
			)
			(layer "F.SilkS")
		)
		(fp_line
			(start -1.524 -0.762)
			(end 1.524 -0.762)
			(stroke
				(width 0.1524)
				(type default)
			)
			(layer "F.SilkS")
		)
		(fp_line
			(start 1.524 0.762)
			(end -1.524 0.762)
			(stroke
				(width 0.1524)
				(type default)
			)
			(layer "F.SilkS")
		)
		(fp_line
			(start -1.524 0.762)
			(end -1.524 -0.762)
			(stroke
				(width 0.1524)
				(type default)
			)
			(layer "F.SilkS")
		)
		(fp_line
			(start 1.1049 -0.724916)
			(end -1.1049 -0.724916)
			(stroke
				(width 0.1)
				(type default)
			)
			(layer "F.Fab")
		)
		(fp_line
			(start -1.1049 -0.724916)
			(end -1.1049 0.724916)
			(stroke
				(width 0.1)
				(type default)
			)
			(layer "F.Fab")
		)
		(fp_line
			(start 1.1049 0.724916)
			(end 1.1049 -0.724916)
			(stroke
				(width 0.1)
				(type default)
			)
			(layer "F.Fab")
		)
		(fp_line
			(start -1.1049 0.724916)
			(end 1.1049 0.724916)
			(stroke
				(width 0.1)
				(type default)
			)
			(layer "F.Fab")
		)
		(pad "1" smd rect
			(at -0.889 0 270)
			(size 1.016 1.27)
			(layers "F.Cu" "F.Mask" "F.Paste")
			(net "P1V8_PEX_R")
		)
		(pad "2" smd rect
			(at 0.889 0 270)
			(size 1.016 1.27)
			(layers "F.Cu" "F.Mask" "F.Paste")
			(net "GND")
		)
	)
	(footprint ""
		(layer "F.Cu")
		(at 142.343886 -45.88891)
		(property "Reference" "R554"
			(at 0 0 0)
			(layer "F.SilkS")
			(hide yes)
			(effects
				(font
					(size 1.27 1.27)
				)
			)
		)
		(property "Value" ""
			(at 0 0 0)
			(layer "F.Fab")
			(effects
				(font
					(size 1.27 1.27)
				)
			)
		)
		(duplicate_pad_numbers_are_jumpers no)
		(fp_line
			(start -0.7874 -0.4064)
			(end 0.7874 -0.4064)
			(stroke
				(width 0.1524)
				(type default)
			)
			(layer "F.SilkS")
		)
		(fp_line
			(start -0.7874 0.4064)
			(end -0.7874 -0.4064)
			(stroke
				(width 0.1524)
				(type default)
			)
			(layer "F.SilkS")
		)
		(fp_line
			(start 0.7874 -0.4064)
			(end 0.7874 0.4064)
			(stroke
				(width 0.1524)
				(type default)
			)
			(layer "F.SilkS")
		)
		(fp_line
			(start 0.7874 0.4064)
			(end -0.7874 0.4064)
			(stroke
				(width 0.1524)
				(type default)
			)
			(layer "F.SilkS")
		)
		(fp_line
			(start -0.67945 -0.305054)
			(end -0.12065 -0.305054)
			(stroke
				(width 0.1)
				(type default)
			)
			(layer "F.Fab")
		)
		(fp_line
			(start -0.67945 0.3048)
			(end -0.67945 -0.305054)
			(stroke
				(width 0.1)
				(type default)
			)
			(layer "F.Fab")
		)
		(fp_line
			(start -0.12065 -0.305054)
			(end -0.12065 -0.2794)
			(stroke
				(width 0.1)
				(type default)
			)
			(layer "F.Fab")
		)
		(fp_line
			(start -0.12065 -0.2794)
			(end 0.12065 -0.2794)
			(stroke
				(width 0.1)
				(type default)
			)
			(layer "F.Fab")
		)
		(fp_line
			(start -0.12065 0.2794)
			(end -0.12065 0.3048)
			(stroke
				(width 0.1)
				(type default)
			)
			(layer "F.Fab")
		)
		(fp_line
			(start -0.12065 0.3048)
			(end -0.67945 0.3048)
			(stroke
				(width 0.1)
				(type default)
			)
			(layer "F.Fab")
		)
		(fp_line
			(start 0.120396 0.2794)
			(end -0.12065 0.2794)
			(stroke
				(width 0.1)
				(type default)
			)
			(layer "F.Fab")
		)
		(fp_line
			(start 0.120396 0.3048)
			(end 0.120396 0.2794)
			(stroke
				(width 0.1)
				(type default)
			)
			(layer "F.Fab")
		)
		(fp_line
			(start 0.12065 -0.3048)
			(end 0.67945 -0.3048)
			(stroke
				(width 0.1)
				(type default)
			)
			(layer "F.Fab")
		)
		(fp_line
			(start 0.12065 -0.2794)
			(end 0.12065 -0.3048)
			(stroke
				(width 0.1)
				(type default)
			)
			(layer "F.Fab")
		)
		(fp_line
			(start 0.67945 -0.3048)
			(end 0.67945 0.3048)
			(stroke
				(width 0.1)
				(type default)
			)
			(layer "F.Fab")
		)
		(fp_line
			(start 0.67945 0.3048)
			(end 0.120396 0.3048)
			(stroke
				(width 0.1)
				(type default)
			)
			(layer "F.Fab")
		)
		(pad "1" smd circle
			(at -0.40005 0)
			(size 0 0)
			(layers "F.Cu" "F.Mask" "F.Paste")
			(net "SSD4_ADC_A0")
		)
		(pad "2" smd circle
			(at 0.40005 0)
			(size 0 0)
			(layers "F.Cu" "F.Mask" "F.Paste")
			(net "GND")
		)
	)
	(footprint ""
		(layer "F.Cu")
		(at 236.909864 -227.737416 90)
		(property "Reference" "R6595"
			(at 0 0 90)
			(layer "F.SilkS")
			(hide yes)
			(effects
				(font
					(size 1.27 1.27)
				)
			)
		)
		(property "Value" ""
			(at 0 0 90)
			(layer "F.Fab")
			(effects
				(font
					(size 1.27 1.27)
				)
			)
		)
		(duplicate_pad_numbers_are_jumpers no)
		(fp_line
			(start 0.7874 -0.4064)
			(end 0.7874 0.4064)
			(stroke
				(width 0.1524)
				(type default)
			)
			(layer "F.SilkS")
		)
		(fp_line
			(start -0.7874 -0.4064)
			(end 0.7874 -0.4064)
			(stroke
				(width 0.1524)
				(type default)
			)
			(layer "F.SilkS")
		)
		(fp_line
			(start 0.7874 0.4064)
			(end -0.7874 0.4064)
			(stroke
				(width 0.1524)
				(type default)
			)
			(layer "F.SilkS")
		)
		(fp_line
			(start -0.7874 0.4064)
			(end -0.7874 -0.4064)
			(stroke
				(width 0.1524)
				(type default)
			)
			(layer "F.SilkS")
		)
		(fp_line
			(start -0.12065 -0.305054)
			(end -0.12065 -0.2794)
			(stroke
				(width 0.1)
				(type default)
			)
			(layer "F.Fab")
		)
		(fp_line
			(start -0.67945 -0.305054)
			(end -0.12065 -0.305054)
			(stroke
				(width 0.1)
				(type default)
			)
			(layer "F.Fab")
		)
		(fp_line
			(start 0.67945 -0.3048)
			(end 0.67945 0.3048)
			(stroke
				(width 0.1)
				(type default)
			)
			(layer "F.Fab")
		)
		(fp_line
			(start 0.12065 -0.3048)
			(end 0.67945 -0.3048)
			(stroke
				(width 0.1)
				(type default)
			)
			(layer "F.Fab")
		)
		(fp_line
			(start 0.12065 -0.2794)
			(end 0.12065 -0.3048)
			(stroke
				(width 0.1)
				(type default)
			)
			(layer "F.Fab")
		)
		(fp_line
			(start -0.12065 -0.2794)
			(end 0.12065 -0.2794)
			(stroke
				(width 0.1)
				(type default)
			)
			(layer "F.Fab")
		)
		(fp_line
			(start 0.120396 0.2794)
			(end -0.12065 0.2794)
			(stroke
				(width 0.1)
				(type default)
			)
			(layer "F.Fab")
		)
		(fp_line
			(start -0.12065 0.2794)
			(end -0.12065 0.3048)
			(stroke
				(width 0.1)
				(type default)
			)
			(layer "F.Fab")
		)
		(fp_line
			(start 0.67945 0.3048)
			(end 0.120396 0.3048)
			(stroke
				(width 0.1)
				(type default)
			)
			(layer "F.Fab")
		)
		(fp_line
			(start 0.120396 0.3048)
			(end 0.120396 0.2794)
			(stroke
				(width 0.1)
				(type default)
			)
			(layer "F.Fab")
		)
		(fp_line
			(start -0.12065 0.3048)
			(end -0.67945 0.3048)
			(stroke
				(width 0.1)
				(type default)
			)
			(layer "F.Fab")
		)
		(fp_line
			(start -0.67945 0.3048)
			(end -0.67945 -0.305054)
			(stroke
				(width 0.1)
				(type default)
			)
			(layer "F.Fab")
		)
		(pad "1" smd circle
			(at -0.40005 0 90)
			(size 0 0)
			(layers "F.Cu" "F.Mask" "F.Paste")
			(net "P1V8_PLL0_PEX2_SCALED")
		)
		(pad "2" smd circle
			(at 0.40005 0 90)
			(size 0 0)
			(layers "F.Cu" "F.Mask" "F.Paste")
			(net "GND")
		)
	)
	(footprint ""
		(layer "F.Cu")
		(at 224.851976 -372.074186 180)
		(property "Reference" "PC12"
			(at 0 0 180)
			(layer "F.SilkS")
			(hide yes)
			(effects
				(font
					(size 1.27 1.27)
				)
			)
		)
		(property "Value" ""
			(at 0 0 180)
			(layer "F.Fab")
			(effects
				(font
					(size 1.27 1.27)
				)
			)
		)
		(duplicate_pad_numbers_are_jumpers no)
		(fp_line
			(start 0.7874 0.4064)
			(end -0.7874 0.4064)
			(stroke
				(width 0.1524)
				(type default)
			)
			(layer "F.SilkS")
		)
		(fp_line
			(start 0.7874 -0.4064)
			(end 0.7874 0.4064)
			(stroke
				(width 0.1524)
				(type default)
			)
			(layer "F.SilkS")
		)
		(fp_line
			(start -0.7874 0.4064)
			(end -0.7874 -0.4064)
			(stroke
				(width 0.1524)
				(type default)
			)
			(layer "F.SilkS")
		)
		(fp_line
			(start -0.7874 -0.4064)
			(end 0.7874 -0.4064)
			(stroke
				(width 0.1524)
				(type default)
			)
			(layer "F.SilkS")
		)
		(fp_line
			(start 0.67945 0.3048)
			(end 0.120396 0.3048)
			(stroke
				(width 0.1)
				(type default)
			)
			(layer "F.Fab")
		)
		(fp_line
			(start 0.67945 -0.3048)
			(end 0.67945 0.3048)
			(stroke
				(width 0.1)
				(type default)
			)
			(layer "F.Fab")
		)
		(fp_line
			(start 0.12065 -0.2794)
			(end 0.12065 -0.3048)
			(stroke
				(width 0.1)
				(type default)
			)
			(layer "F.Fab")
		)
		(fp_line
			(start 0.12065 -0.3048)
			(end 0.67945 -0.3048)
			(stroke
				(width 0.1)
				(type default)
			)
			(layer "F.Fab")
		)
		(fp_line
			(start 0.120396 0.3048)
			(end 0.120396 0.2794)
			(stroke
				(width 0.1)
				(type default)
			)
			(layer "F.Fab")
		)
		(fp_line
			(start 0.120396 0.2794)
			(end -0.12065 0.2794)
			(stroke
				(width 0.1)
				(type default)
			)
			(layer "F.Fab")
		)
		(fp_line
			(start -0.12065 0.3048)
			(end -0.67945 0.3048)
			(stroke
				(width 0.1)
				(type default)
			)
			(layer "F.Fab")
		)
		(fp_line
			(start -0.12065 0.2794)
			(end -0.12065 0.3048)
			(stroke
				(width 0.1)
				(type default)
			)
			(layer "F.Fab")
		)
		(fp_line
			(start -0.12065 -0.2794)
			(end 0.12065 -0.2794)
			(stroke
				(width 0.1)
				(type default)
			)
			(layer "F.Fab")
		)
		(fp_line
			(start -0.12065 -0.305054)
			(end -0.12065 -0.2794)
			(stroke
				(width 0.1)
				(type default)
			)
			(layer "F.Fab")
		)
		(fp_line
			(start -0.67945 0.3048)
			(end -0.67945 -0.305054)
			(stroke
				(width 0.1)
				(type default)
			)
			(layer "F.Fab")
		)
		(fp_line
			(start -0.67945 -0.305054)
			(end -0.12065 -0.305054)
			(stroke
				(width 0.1)
				(type default)
			)
			(layer "F.Fab")
		)
		(pad "1" smd circle
			(at -0.40005 0 180)
			(size 0 0)
			(layers "F.Cu" "F.Mask" "F.Paste")
			(net "HSC_SS")
		)
		(pad "2" smd circle
			(at 0.40005 0 180)
			(size 0 0)
			(layers "F.Cu" "F.Mask" "F.Paste")
			(net "AGND_HSC")
		)
	)
)
